# SCM (Grand Teton) — schematic netlist excerpt (pin names and nets, part order shuffled) for the footprints in the layout excerpt that follows; sources: Cadence DE-HDL packaged netlist, KiCad conversion of 12092022_DA0F0TMDCD0_F0T_Management_Board_D_brd_V3_OCP.brd

C260  Q_CAP  0.1UF 25V 10% X7R  pkg 0402  page 41 : A = VCCIO2 ; B = GND
R628  Q_RES  100 1% CHIP  pkg 0402LF  page 31 : A = SPA_SIN_SW_DBG ; B = SPA_SIN_SW_DBG_R

(kicad_pcb
	(version 20260206)
	(generator "pcbnew")
	(generator_version "10.0")
	(general
		(thickness 1.6)
		(legacy_teardrops no)
	)
	(paper "A4")
	(title_block
		(title "12092022_DA0F0TMDCD0_F0T_Management_Board_D_brd_V3_OCP.brd")
		(comment 1 "Grand Teton / footprints 1193-1194 of 1440")
	)
	(layers
		(0 "F.Cu" signal "TOP")
		(4 "In1.Cu" signal "GND")
		(6 "In2.Cu" signal "IN1")
		(8 "In3.Cu" signal "GND1")
		(10 "In4.Cu" signal "IN2")
		(12 "In5.Cu" signal "VCC")
		(14 "In6.Cu" signal "VCC1")
		(16 "In7.Cu" signal "IN3")
		(18 "In8.Cu" signal "GND2")
		(20 "In9.Cu" signal "IN4")
		(22 "In10.Cu" signal "GND3")
		(2 "B.Cu" signal "BOTTOM")
		(9 "F.Adhes" user "F.Adhesive")
		(11 "B.Adhes" user "B.Adhesive")
		(13 "F.Paste" user "Package Geometry/Pastemask Top")
		(15 "B.Paste" user "Package Geometry/Pastemask Bottom")
		(5 "F.SilkS" user "Ref Des/Silkscreen Top")
		(7 "B.SilkS" user "Ref Des/Silkscreen Bottom")
		(1 "F.Mask" user "Board Geometry/Soldermask Top")
		(3 "B.Mask" user "Board Geometry/Soldermask Bottom")
		(17 "Dwgs.User" user "User.Drawings")
		(19 "Cmts.User" user "User.Comments")
		(21 "Eco1.User" user "User.Eco1")
		(23 "Eco2.User" user "User.Eco2")
		(25 "Edge.Cuts" user "Board Geometry/Outline")
		(27 "Margin" user)
		(31 "F.CrtYd" user "Package Geometry/Place Bound Top")
		(29 "B.CrtYd" user "Package Geometry/Place Bound Bottom")
		(35 "F.Fab" user "Ref Des/Assembly Top")
		(33 "B.Fab" user "Ref Des/Assembly Bottom")
	)
	(footprint ""
		(layer "B.Cu")
		(at 32.6644 -71.882 180)
		(property "Reference" "R628"
			(at 0 0 0)
			(layer "B.SilkS")
			(hide yes)
			(effects
				(font
					(size 1.27 1.27)
				)
				(justify mirror)
			)
		)
		(property "Value" ""
			(at 0 0 0)
			(layer "B.Fab")
			(effects
				(font
					(size 1.27 1.27)
				)
				(justify mirror)
			)
		)
		(duplicate_pad_numbers_are_jumpers no)
		(fp_line
			(start 0.7874 0.4064)
			(end 0.7874 -0.4064)
			(stroke
				(width 0.1524)
				(type default)
			)
			(layer "B.SilkS")
		)
		(fp_line
			(start 0.7874 -0.4064)
			(end -0.7874 -0.4064)
			(stroke
				(width 0.1524)
				(type default)
			)
			(layer "B.SilkS")
		)
		(fp_line
			(start -0.7874 0.4064)
			(end 0.7874 0.4064)
			(stroke
				(width 0.1524)
				(type default)
			)
			(layer "B.SilkS")
		)
		(fp_line
			(start -0.7874 -0.4064)
			(end -0.7874 0.4064)
			(stroke
				(width 0.1524)
				(type default)
			)
			(layer "B.SilkS")
		)
		(fp_line
			(start 0.67945 0.3048)
			(end 0.67945 -0.305054)
			(stroke
				(width 0.1)
				(type default)
			)
			(layer "B.Fab")
		)
		(fp_line
			(start 0.67945 -0.305054)
			(end 0.12065 -0.305054)
			(stroke
				(width 0.1)
				(type default)
			)
			(layer "B.Fab")
		)
		(fp_line
			(start 0.12065 0.3048)
			(end 0.67945 0.3048)
			(stroke
				(width 0.1)
				(type default)
			)
			(layer "B.Fab")
		)
		(fp_line
			(start 0.12065 0.2794)
			(end 0.12065 0.3048)
			(stroke
				(width 0.1)
				(type default)
			)
			(layer "B.Fab")
		)
		(fp_line
			(start 0.12065 -0.2794)
			(end -0.12065 -0.2794)
			(stroke
				(width 0.1)
				(type default)
			)
			(layer "B.Fab")
		)
		(fp_line
			(start 0.12065 -0.305054)
			(end 0.12065 -0.2794)
			(stroke
				(width 0.1)
				(type default)
			)
			(layer "B.Fab")
		)
		(fp_line
			(start -0.120396 0.3048)
			(end -0.120396 0.2794)
			(stroke
				(width 0.1)
				(type default)
			)
			(layer "B.Fab")
		)
		(fp_line
			(start -0.120396 0.2794)
			(end 0.12065 0.2794)
			(stroke
				(width 0.1)
				(type default)
			)
			(layer "B.Fab")
		)
		(fp_line
			(start -0.12065 -0.2794)
			(end -0.12065 -0.3048)
			(stroke
				(width 0.1)
				(type default)
			)
			(layer "B.Fab")
		)
		(fp_line
			(start -0.12065 -0.3048)
			(end -0.67945 -0.3048)
			(stroke
				(width 0.1)
				(type default)
			)
			(layer "B.Fab")
		)
		(fp_line
			(start -0.67945 0.3048)
			(end -0.120396 0.3048)
			(stroke
				(width 0.1)
				(type default)
			)
			(layer "B.Fab")
		)
		(fp_line
			(start -0.67945 -0.3048)
			(end -0.67945 0.3048)
			(stroke
				(width 0.1)
				(type default)
			)
			(layer "B.Fab")
		)
		(pad "1" smd circle
			(at 0.40005 0)
			(size 0 0)
			(layers "B.Cu" "B.Mask" "B.Paste")
			(net "SPA_SIN_SW_DBG")
		)
		(pad "2" smd circle
			(at -0.40005 0)
			(size 0 0)
			(layers "B.Cu" "B.Mask" "B.Paste")
			(net "SPA_SIN_SW_DBG_R")
		)
	)
	(footprint ""
		(layer "B.Cu")
		(at 25.060656 -97.5868 -90)
		(property "Reference" "C260"
			(at 0 0 90)
			(layer "B.SilkS")
			(hide yes)
			(effects
				(font
					(size 1.27 1.27)
				)
				(justify mirror)
			)
		)
		(property "Value" ""
			(at 0 0 90)
			(layer "B.Fab")
			(effects
				(font
					(size 1.27 1.27)
				)
				(justify mirror)
			)
		)
		(duplicate_pad_numbers_are_jumpers no)
		(fp_line
			(start -0.69215 0.2921)
			(end 0.69215 0.2921)
			(stroke
				(width 0.1524)
				(type default)
			)
			(layer "B.SilkS")
		)
		(fp_line
			(start 0.69215 0.2921)
			(end 0.69215 -0.2921)
			(stroke
				(width 0.1524)
				(type default)
			)
			(layer "B.SilkS")
		)
		(fp_line
			(start -0.69215 -0.2921)
			(end -0.69215 0.2921)
			(stroke
				(width 0.1524)
				(type default)
			)
			(layer "B.SilkS")
		)
		(fp_line
			(start 0.69215 -0.2921)
			(end -0.69215 -0.2921)
			(stroke
				(width 0.1524)
				(type default)
			)
			(layer "B.SilkS")
		)
		(fp_line
			(start -0.51435 0.2794)
			(end 0.51435 0.2794)
			(stroke
				(width 0.1)
				(type default)
			)
			(layer "B.Fab")
		)
		(fp_line
			(start 0.51435 0.2794)
			(end 0.51435 -0.2794)
			(stroke
				(width 0.1)
				(type default)
			)
			(layer "B.Fab")
		)
		(fp_line
			(start -0.51435 -0.2794)
			(end -0.51435 0.2794)
			(stroke
				(width 0.1)
				(type default)
			)
			(layer "B.Fab")
		)
		(fp_line
			(start 0.51435 -0.2794)
			(end -0.51435 -0.2794)
			(stroke
				(width 0.1)
				(type default)
			)
			(layer "B.Fab")
		)
		(pad "1" smd circle
			(at 0.40005 0 90)
			(size 0 0)
			(layers "B.Cu" "B.Mask" "B.Paste")
			(net "VCCIO2")
		)
		(pad "2" smd circle
			(at -0.40005 0 90)
			(size 0 0)
			(layers "B.Cu" "B.Mask" "B.Paste")
			(net "GND")
		)
		(zone
			(layer "B.Cu")
			(hatch none 0.5)
			(connect_pads
				(clearance 0)
			)
			(min_thickness 0.25)
			(keepout
				(tracks not_allowed)
				(vias allowed)
				(pads allowed)
				(copperpour not_allowed)
				(footprints allowed)
			)
			(placement
				(enabled no)
				(sheetname "")
			)
			(fill
				(thermal_gap 0.5)
				(thermal_bridge_width 0.5)
				(island_removal_mode 0)
			)
			(polygon
				(pts
					(xy 24.973026 -97.3963) (xy 24.91486 -97.48774) (xy 24.91486 -97.68713) (xy 24.973026 -97.7773)
					(xy 25.148286 -97.7773) (xy 25.206706 -97.68713) (xy 25.206706 -97.48774) (xy 25.14854 -97.3963)
				)
			)
		)
	)
)
